# T6G (Grand Teton) — schematic netlist excerpt (pin names and nets, part order shuffled) for the footprints in the layout excerpt that follows; sources: Cadence DE-HDL packaged netlist, KiCad conversion of 04192023_DAF0TMB3IC0_F0TG_MB_C_brd_V02_OCP.brd

R3522  Q_RES  54.9K 1% CHIP  pkg 0402LF  page 248 : A = P3V3_AUX ; B = SMB_2_BMC_GPU_BUF_R_SDA
PC262_1  Q_CAP  1UF 25V 10% X6S  pkg C0402  page 211 : A = SW_P12V_AUX_PVDDCR_CPU0_P1_FLT ; B = GND

(kicad_pcb
	(version 20260206)
	(generator "pcbnew")
	(generator_version "10.0")
	(general
		(thickness 1.6)
		(legacy_teardrops no)
	)
	(paper "A4")
	(title_block
		(title "04192023_DAF0TMB3IC0_F0TG_MB_C_brd_V02_OCP.brd")
		(comment 1 "Grand Teton / footprints 1352-1353 of 8354")
	)
	(layers
		(0 "F.Cu" signal "TOP")
		(4 "In1.Cu" signal "GND")
		(6 "In2.Cu" signal "IN1")
		(8 "In3.Cu" signal "GND1")
		(10 "In4.Cu" signal "IN2")
		(12 "In5.Cu" signal "GND2")
		(14 "In6.Cu" signal "IN3")
		(16 "In7.Cu" signal "GND3")
		(18 "In8.Cu" signal "VCC")
		(20 "In9.Cu" signal "VCC1")
		(22 "In10.Cu" signal "GND4")
		(24 "In11.Cu" signal "IN4")
		(26 "In12.Cu" signal "GND5")
		(28 "In13.Cu" signal "IN5")
		(30 "In14.Cu" signal "GND6")
		(32 "In15.Cu" signal "IN6")
		(34 "In16.Cu" signal "GND7")
		(2 "B.Cu" signal "BOTTOM")
		(9 "F.Adhes" user "F.Adhesive")
		(11 "B.Adhes" user "B.Adhesive")
		(13 "F.Paste" user "Package Geometry/Pastemask Top")
		(15 "B.Paste" user "Package Geometry/Pastemask Bottom")
		(5 "F.SilkS" user "Ref Des/Silkscreen Top")
		(7 "B.SilkS" user "Ref Des/Silkscreen Bottom")
		(1 "F.Mask" user "Board Geometry/Soldermask Top")
		(3 "B.Mask" user "Board Geometry/Soldermask Bottom")
		(17 "Dwgs.User" user "User.Drawings")
		(19 "Cmts.User" user "User.Comments")
		(21 "Eco1.User" user "User.Eco1")
		(23 "Eco2.User" user "User.Eco2")
		(25 "Edge.Cuts" user "Board Geometry/Outline")
		(27 "Margin" user)
		(31 "F.CrtYd" user "Package Geometry/Place Bound Top")
		(29 "B.CrtYd" user "Package Geometry/Place Bound Bottom")
		(35 "F.Fab" user "Ref Des/Assembly Top")
		(33 "B.Fab" user "Ref Des/Assembly Bottom")
	)
	(footprint ""
		(layer "F.Cu")
		(at 78.65237 -182.585106 90)
		(property "Reference" "PC262_1"
			(at 0 0 90)
			(layer "F.SilkS")
			(hide yes)
			(effects
				(font
					(size 1.27 1.27)
				)
			)
		)
		(property "Value" ""
			(at 0 0 90)
			(layer "F.Fab")
			(effects
				(font
					(size 1.27 1.27)
				)
			)
		)
		(duplicate_pad_numbers_are_jumpers no)
		(fp_line
			(start 0.7874 -0.4064)
			(end 0.7874 0.4064)
			(stroke
				(width 0.1524)
				(type default)
			)
			(layer "F.SilkS")
		)
		(fp_line
			(start -0.7874 -0.4064)
			(end 0.7874 -0.4064)
			(stroke
				(width 0.1524)
				(type default)
			)
			(layer "F.SilkS")
		)
		(fp_line
			(start 0.7874 0.4064)
			(end -0.7874 0.4064)
			(stroke
				(width 0.1524)
				(type default)
			)
			(layer "F.SilkS")
		)
		(fp_line
			(start -0.7874 0.4064)
			(end -0.7874 -0.4064)
			(stroke
				(width 0.1524)
				(type default)
			)
			(layer "F.SilkS")
		)
		(fp_line
			(start -0.12065 -0.305054)
			(end -0.12065 -0.2794)
			(stroke
				(width 0.1)
				(type default)
			)
			(layer "F.Fab")
		)
		(fp_line
			(start -0.67945 -0.305054)
			(end -0.12065 -0.305054)
			(stroke
				(width 0.1)
				(type default)
			)
			(layer "F.Fab")
		)
		(fp_line
			(start 0.67945 -0.3048)
			(end 0.67945 0.3048)
			(stroke
				(width 0.1)
				(type default)
			)
			(layer "F.Fab")
		)
		(fp_line
			(start 0.12065 -0.3048)
			(end 0.67945 -0.3048)
			(stroke
				(width 0.1)
				(type default)
			)
			(layer "F.Fab")
		)
		(fp_line
			(start 0.12065 -0.2794)
			(end 0.12065 -0.3048)
			(stroke
				(width 0.1)
				(type default)
			)
			(layer "F.Fab")
		)
		(fp_line
			(start -0.12065 -0.2794)
			(end 0.12065 -0.2794)
			(stroke
				(width 0.1)
				(type default)
			)
			(layer "F.Fab")
		)
		(fp_line
			(start 0.120396 0.2794)
			(end -0.12065 0.2794)
			(stroke
				(width 0.1)
				(type default)
			)
			(layer "F.Fab")
		)
		(fp_line
			(start -0.12065 0.2794)
			(end -0.12065 0.3048)
			(stroke
				(width 0.1)
				(type default)
			)
			(layer "F.Fab")
		)
		(fp_line
			(start 0.67945 0.3048)
			(end 0.120396 0.3048)
			(stroke
				(width 0.1)
				(type default)
			)
			(layer "F.Fab")
		)
		(fp_line
			(start 0.120396 0.3048)
			(end 0.120396 0.2794)
			(stroke
				(width 0.1)
				(type default)
			)
			(layer "F.Fab")
		)
		(fp_line
			(start -0.12065 0.3048)
			(end -0.67945 0.3048)
			(stroke
				(width 0.1)
				(type default)
			)
			(layer "F.Fab")
		)
		(fp_line
			(start -0.67945 0.3048)
			(end -0.67945 -0.305054)
			(stroke
				(width 0.1)
				(type default)
			)
			(layer "F.Fab")
		)
		(pad "1" smd circle
			(at -0.40005 0 90)
			(size 0 0)
			(layers "F.Cu" "F.Mask" "F.Paste")
			(net "SW_P12V_AUX_PVDDCR_CPU0_P1_FLT")
		)
		(pad "2" smd circle
			(at 0.40005 0 90)
			(size 0 0)
			(layers "F.Cu" "F.Mask" "F.Paste")
			(net "GND")
		)
	)
	(footprint ""
		(layer "F.Cu")
		(at 22.036278 -436.964074)
		(property "Reference" "R3522"
			(at 0 0 0)
			(layer "F.SilkS")
			(hide yes)
			(effects
				(font
					(size 1.27 1.27)
				)
			)
		)
		(property "Value" ""
			(at 0 0 0)
			(layer "F.Fab")
			(effects
				(font
					(size 1.27 1.27)
				)
			)
		)
		(duplicate_pad_numbers_are_jumpers no)
		(fp_line
			(start -0.7874 -0.4064)
			(end 0.7874 -0.4064)
			(stroke
				(width 0.1524)
				(type default)
			)
			(layer "F.SilkS")
		)
		(fp_line
			(start -0.7874 0.4064)
			(end -0.7874 -0.4064)
			(stroke
				(width 0.1524)
				(type default)
			)
			(layer "F.SilkS")
		)
		(fp_line
			(start 0.7874 -0.4064)
			(end 0.7874 0.4064)
			(stroke
				(width 0.1524)
				(type default)
			)
			(layer "F.SilkS")
		)
		(fp_line
			(start 0.7874 0.4064)
			(end -0.7874 0.4064)
			(stroke
				(width 0.1524)
				(type default)
			)
			(layer "F.SilkS")
		)
		(fp_line
			(start -0.67945 -0.305054)
			(end -0.12065 -0.305054)
			(stroke
				(width 0.1)
				(type default)
			)
			(layer "F.Fab")
		)
		(fp_line
			(start -0.67945 0.3048)
			(end -0.67945 -0.305054)
			(stroke
				(width 0.1)
				(type default)
			)
			(layer "F.Fab")
		)
		(fp_line
			(start -0.12065 -0.305054)
			(end -0.12065 -0.2794)
			(stroke
				(width 0.1)
				(type default)
			)
			(layer "F.Fab")
		)
		(fp_line
			(start -0.12065 -0.2794)
			(end 0.12065 -0.2794)
			(stroke
				(width 0.1)
				(type default)
			)
			(layer "F.Fab")
		)
		(fp_line
			(start -0.12065 0.2794)
			(end -0.12065 0.3048)
			(stroke
				(width 0.1)
				(type default)
			)
			(layer "F.Fab")
		)
		(fp_line
			(start -0.12065 0.3048)
			(end -0.67945 0.3048)
			(stroke
				(width 0.1)
				(type default)
			)
			(layer "F.Fab")
		)
		(fp_line
			(start 0.120396 0.2794)
			(end -0.12065 0.2794)
			(stroke
				(width 0.1)
				(type default)
			)
			(layer "F.Fab")
		)
		(fp_line
			(start 0.120396 0.3048)
			(end 0.120396 0.2794)
			(stroke
				(width 0.1)
				(type default)
			)
			(layer "F.Fab")
		)
		(fp_line
			(start 0.12065 -0.3048)
			(end 0.67945 -0.3048)
			(stroke
				(width 0.1)
				(type default)
			)
			(layer "F.Fab")
		)
		(fp_line
			(start 0.12065 -0.2794)
			(end 0.12065 -0.3048)
			(stroke
				(width 0.1)
				(type default)
			)
			(layer "F.Fab")
		)
		(fp_line
			(start 0.67945 -0.3048)
			(end 0.67945 0.3048)
			(stroke
				(width 0.1)
				(type default)
			)
			(layer "F.Fab")
		)
		(fp_line
			(start 0.67945 0.3048)
			(end 0.120396 0.3048)
			(stroke
				(width 0.1)
				(type default)
			)
			(layer "F.Fab")
		)
		(pad "1" smd circle
			(at -0.40005 0)
			(size 0 0)
			(layers "F.Cu" "F.Mask" "F.Paste")
			(net "P3V3_AUX")
		)
		(pad "2" smd circle
			(at 0.40005 0)
			(size 0 0)
			(layers "F.Cu" "F.Mask" "F.Paste")
			(net "SMB_2_BMC_GPU_BUF_R_SDA")
		)
	)
)
